FILE_TYPE = CONNECTIVITY;
{Allegro Design Entry HDL 17.4-2019 S026 (4007227) 1/17/2022}
"PAGE_NUMBER" = 469;
0"NC";
1"GND\g";
2"GND\g";
3"GND\g";
4"P3V3_AUX\g";
5"GND\g";
6"GND\g";
7"GND\g";
8"GND\g";
9"P3V3_AUX\g";
10"GND\g";
11"GND\g";
12"SW_P1V8_RETIMER_CPU0_SW";
13"PWRGD_P1V8_RETIMER_CPU0";
14"GND\g";
15"GND\g";
16"GND\g";
17"P1V8_CPU0_RT_1D\g";
18"P12V_AUX\g";
19"P1V8_RETIMER_CPU0_EN";
20"FM_PWRGD_P1V8_RETIMER_CPU0";
21"P1V8_RETIMER_CPU0_FB";
22"SW_P1V8_RETIMER_CPU0_BST";
23"P1V8_RETIMER_CPU0_MODE";
24"P1V8_RETIMER_CPU0_REF";
25"SW_P1V8_RETIMER_CPU0_BST_R";
26"P1V8_RETIMER_CPU0_CS";
27"P1V8_RETIMER_CPU0_VCC";
28"SW_P12V_AUX_P1V8_RETIMER_CPU0_FLT";
%"UNIVERSAL_GND"
"1","(-8450,3000)","0","pure_quanta_power","I1";
;
CDS_LIB"pure_quanta_power"
HDL_POWER"GND";
"A"1;
%"UNIVERSAL_GND"
"1","(-7925,2750)","0","pure_quanta_power","I10";
;
CDS_LIB"pure_quanta_power"
HDL_POWER"GND";
"A"2;
%"UNIVERSAL_GND"
"1","(-7450,2150)","0","pure_quanta_power","I11";
;
CDS_LIB"pure_quanta_power"
HDL_POWER"GND";
"A"3;
%"Q_CAP"
"1","(-7450,2375)","2","pure_quanta","I12";
;
LOCATION"PC6506"
SEC"1"
TOLERANCE"10%"
VALUE"1UF"
VOLTAGE"25V"
MATERIAL"X6S"
PACK_TYPE"C0402"
SEC_TYPE"C0402"
SIGNAL_MODEL"DEFAULT_CAPACITOR_100000PF_2_1"
CDS_LIB"pure_quanta"
PART_NUMBER"CH5104KEB02";
"B"
$PN"2"3;
"A"
$PN"1"27;
%"Q_RES"
"2","(-7450,2800)","0","pure_quanta","I13";
;
LOCATION"PR6501"
$SEC"1"
CDS_SEC"1"
PACK_TYPE"0402LF"
MATERIAL"CHIP"
WATTAGE"1/16W"
TOLERANCE"5%"
VALUE"0"
CDS_LIB"pure_quanta"
PART_NUMBER"CS00002JB13";
"A"
$PN"1"4;
"B"
$PN"2"27;
%"UNIVERSAL_POWER"
"1","(-7450,3000)","0","mstr_symbols","I14";
;
HDL_POWER"P3V3_AUX"
CDS_LIB"mstr_symbols";
"A"4;
%"UNIVERSAL_GND"
"1","(-7475,3625)","0","pure_quanta_power","I15";
;
CDS_LIB"pure_quanta_power"
HDL_POWER"GND";
"A"14;
%"Q_CAP"
"1","(-7975,3975)","0","pure_quanta","I16";
;
LOCATION"PC6501"
$SEC"1"
CDS_SEC"1"
VOLTAGE"16V"
PACK_TYPE"C0805"
VALUE"22UF"
TOLERANCE"20%"
MATERIAL"X6S"
CDS_LIB"pure_quanta"
PART_NUMBER"CH6223MEA01";
"B"
$PN"2"14;
"A"
$PN"1"28;
%"Q_CAP"
"1","(-7750,3975)","0","pure_quanta","I17";
;
LOCATION"PC6502"
$SEC"1"
CDS_SEC"1"
MATERIAL"X6S"
VOLTAGE"16V"
VALUE"22UF"
TOLERANCE"20%"
PACK_TYPE"C0805"
CDS_LIB"pure_quanta"
PART_NUMBER"CH6223MEA01";
"B"
$PN"2"14;
"A"
$PN"1"28;
%"Q_CAP"
"1","(-7550,3975)","0","pure_quanta","I18";
;
LOCATION"PC6503"
$SEC"1"
CDS_SEC"1"
PACK_TYPE"C0805"
TOLERANCE"20%"
MATERIAL"X6S"
VOLTAGE"16V"
VALUE"22UF"
CDS_LIB"pure_quanta"
PART_NUMBER"CH6223MEA01";
"B"
$PN"2"14;
"A"
$PN"1"28;
%"UNIVERSAL_GND"
"1","(-6575,2125)","0","pure_quanta_power","I19";
;
CDS_LIB"pure_quanta_power"
HDL_POWER"GND";
"A"5;
%"Q_RES"
"2","(-6575,2375)","0","pure_quanta","I20";
;
LOCATION"PR6502"
SEC"1"
MATERIAL"CHIP"
TOLERANCE"1%"
WATTAGE"1/16W"
PACK_TYPE"0402LF"
VALUE"7.15K"
CDS_LIB"pure_quanta"
SEC_TYPE"0402LF"
PART_NUMBER"CS27152FB03";
"A"
$PN"1"26;
"B"
$PN"2"5;
%"Q_RES"
"1","(-6950,3200)","0","pure_quanta","I21";
;
LOCATION"PR6500"
$SEC"1"
CDS_SEC"1"
WATTAGE"1/16W"
VALUE"0"
MATERIAL"CHIP"
TOLERANCE"5%"
PACK_TYPE"0402LF"
CDS_LIB"pure_quanta"
PART_NUMBER"CS00002JB13";
"B"
$PN"2"23;
"A"
$PN"1"2;
%"Q_CAP"
"1","(-7350,3975)","0","pure_quanta","I22";
;
LOCATION"PC6504"
$SEC"1"
CDS_SEC"1"
PACK_TYPE"C0805"
TOLERANCE"20%"
MATERIAL"X6S"
VALUE"22UF"
VOLTAGE"16V"
CDS_LIB"pure_quanta"
PART_NUMBER"CH6223MEA01";
"B"
$PN"2"14;
"A"
$PN"1"28;
%"Q_CAP"
"1","(-7150,3975)","0","pure_quanta","I23";
;
LOCATION"PC6505"
$SEC"1"
CDS_SEC"1"
VOLTAGE"25V"
VALUE"1UF"
PACK_TYPE"C0402"
TOLERANCE"10%"
MATERIAL"X6S"
CDS_LIB"pure_quanta"
PART_NUMBER"CH5104KEB02";
"B"
$PN"2"14;
"A"
$PN"1"28;
%"UNIVERSAL_GND"
"1","(-5000,2275)","0","pure_quanta_power","I24";
;
CDS_LIB"pure_quanta_power"
HDL_POWER"GND";
"A"15;
%"UNIVERSAL_GND"
"1","(-4875,2275)","0","pure_quanta_power","I25";
;
CDS_LIB"pure_quanta_power"
HDL_POWER"GND";
"A"6;
%"Q_CAP"
"1","(-4875,2525)","0","pure_quanta","I26";
;
LOCATION"PC6518"
$SEC"1"
CDS_SEC"1"
VOLTAGE"25V"
TOLERANCE"10%"
MATERIAL"X7R"
VALUE"0.1UF"
PACK_TYPE"0402"
CDS_LIB"pure_quanta"
PART_NUMBER"CH4104K1B00";
"B"
$PN"2"6;
"A"
$PN"1"24;
%"UNIVERSAL_GND"
"1","(-4425,2250)","0","pure_quanta_power","I27";
;
CDS_LIB"pure_quanta_power"
HDL_POWER"GND";
"A"7;
%"Q_RES"
"2","(-4575,4200)","0","pure_quanta","I28";
;
LOCATION"R6505"
SEC"1"
MATERIAL"CHIP"
TOLERANCE"5%"
VALUE"10K"
PACK_TYPE"0402LF"
WATTAGE"1/16W"
SEC_TYPE"0402LF"
CDS_LIB"pure_quanta"
PART_NUMBER"CS31002JB08";
"A"
$PN"1"9;
"B"
$PN"2"13;
%"Q_RES"
"1","(-4450,3700)","0","pure_quanta","I29";
;
LOCATION"PR6800"
$SEC"1"
CDS_SEC"1"
VALUE"2.2"
PACK_TYPE"0402LF"
MATERIAL"CHIP"
CDS_LIB"pure_quanta"
WATTAGE"1/16W"
TOLERANCE"1%"
PART_NUMBER"CS-2202FB01";
"B"
$PN"2"25;
"A"
$PN"1"22;
%"UNIVERSAL_GND"
"1","(-9100,3650)","0","pure_quanta_power","I3";
;
CDS_LIB"pure_quanta_power"
HDL_POWER"GND";
"A"8;
%"UNIVERSAL_POWER"
"1","(-4575,4475)","0","mstr_symbols","I30";
;
HDL_POWER"P3V3_AUX"
CDS_LIB"mstr_symbols";
"A"9;
%"UNIVERSAL_GND"
"1","(-4025,2175)","0","pure_quanta_power","I31";
;
CDS_LIB"pure_quanta_power"
HDL_POWER"GND";
"A"10;
%"Q_CAP"
"1","(-4025,3550)","0","pure_quanta","I32";
;
LOCATION"PC6507"
SEC"1"
MATERIAL"X7R"
TOLERANCE"10%"
VOLTAGE"16V"
PACK_TYPE"0402"
VALUE"0.22UF"
CDS_LIB"pure_quanta"
SEC_TYPE"0402"
PART_NUMBER"CH4223K1B00";
"B"
$PN"2"12;
"A"
$PN"1"25;
%"Q_RES"
"2","(-4025,2425)","0","pure_quanta","I33";
;
LOCATION"PR6507"
$SEC"1"
CDS_SEC"1"
VALUE"10K"
TOLERANCE"1%"
MATERIAL"CHIP"
PACK_TYPE"0402LF"
WATTAGE"1/16W"
CDS_LIB"pure_quanta"
PART_NUMBER"CS31002FB08";
"A"
$PN"1"21;
"B"
$PN"2"10;
%"Q_CAP"
"2","(-3450,2625)","0","pure_quanta","I34";
;
LOCATION"PC6515"
$SEC"1"
CDS_SEC"1"
TOLERANCE"5%"
VALUE"150PF"
PACK_TYPE"0402"
VOLTAGE"50V"
MATERIAL"NPO"
CDS_LIB"pure_quanta"
PART_NUMBER"TMP_QCH11506JB08";
"A"
$PN"1"21;
"B"
$PN"2"17;
%"Q_RES"
"1","(-3450,2950)","0","pure_quanta","I35";
;
LOCATION"PR6505"
$SEC"1"
CDS_SEC"1"
PACK_TYPE"0402LF"
MATERIAL"CHIP"
VALUE"20K"
TOLERANCE"1%"
WATTAGE"1/16W"
CDS_LIB"pure_quanta"
PART_NUMBER"CS32002FB06";
"B"
$PN"2"17;
"A"
$PN"1"21;
%"Q_INDUCTOR"
"1","(-3450,3425)","0","pure_quanta","I36";
;
LOCATION"PL6501"
$SEC"1"
CDS_SEC"1"
MATERIAL"IND"
VALUE"1UH"
PACK_TYPE"SMLF"
NEEDS_NO_SIZE"TRUE"
CDS_LIB"pure_quanta"
PART_NUMBER"CV-10U0MZ01";
"1"
$PN"1"12;
"2"
$PN"2"17;
%"Q_RES"
"1","(-3525,3900)","0","pure_quanta","I37";
;
LOCATION"R6506"
$SEC"1"
CDS_SEC"1"
VALUE"33"
CDS_LIB"pure_quanta"
BOM_COST"MEM"
WATTAGE"1/16W"
MATERIAL"CHIP"
TOLERANCE"5%"
PACK_TYPE"0402LF"
PART_NUMBER"CS03302JB10";
"B"
$PN"2"20;
"A"
$PN"1"13;
%"Q_CAP"
"1","(-2800,3150)","0","pure_quanta","I38";
;
LOCATION"PC6508"
$SEC"1"
CDS_SEC"1"
PACK_TYPE"C0805"
VOLTAGE"4V"
TOLERANCE"20%"
MATERIAL"X6S"
VALUE"22UF"
CDS_LIB"pure_quanta"
PART_NUMBER"CH622KMEA03";
"B"
$PN"2"16;
"A"
$PN"1"17;
%"Q_CAP"
"1","(-2425,3150)","0","pure_quanta","I39";
;
LOCATION"PC6509"
$SEC"1"
CDS_SEC"1"
VOLTAGE"4V"
VALUE"22UF"
PACK_TYPE"C0805"
MATERIAL"X6S"
TOLERANCE"20%"
CDS_LIB"pure_quanta"
PART_NUMBER"CH622KMEA03";
"B"
$PN"2"16;
"A"
$PN"1"17;
%"Q_CAP"
"1","(-9100,3975)","0","pure_quanta","I4";
;
LOCATION"PC6500"
$SEC"1"
CDS_SEC"1"
MATERIAL"X6S"
TOLERANCE"10%"
VOLTAGE"25V"
PACK_TYPE"C0402"
VALUE"0.1UF"
CDS_LIB"pure_quanta"
PART_NUMBER"CH4104KEB00";
"B"
$PN"2"8;
"A"
$PN"1"18;
%"Q_CAP"
"1","(-2150,3150)","0","pure_quanta","I40";
;
LOCATION"PC6510"
$SEC"1"
CDS_SEC"1"
VOLTAGE"4V"
VALUE"22UF"
TOLERANCE"20%"
MATERIAL"X6S"
PACK_TYPE"C0805"
CDS_LIB"pure_quanta"
PART_NUMBER"CH622KMEA03";
"B"
$PN"2"16;
"A"
$PN"1"17;
%"UNIVERSAL_GND"
"1","(-2725,3550)","0","pure_quanta_power","I41";
;
CDS_LIB"pure_quanta_power"
HDL_POWER"GND";
"A"11;
%"Q_CAP"
"1","(-2725,3750)","0","pure_quanta","I42";
;
LOCATION"C6758"
$SEC"1"
CDS_SEC"1"
VOLTAGE"50V"
VALUE"1000PF"
PACK_TYPE"0402"
MATERIAL"X7R"
TOLERANCE"5%"
CDS_LIB"pure_quanta"
PART_NUMBER"TMP_QCH21006JB10";
"B"
$PN"2"11;
"A"
$PN"1"20;
%"Q_CAP"
"1","(-1875,3150)","0","pure_quanta","I44";
;
LOCATION"PC6511"
$SEC"1"
CDS_SEC"1"
VALUE"22UF"
VOLTAGE"4V"
TOLERANCE"20%"
MATERIAL"X6S"
PACK_TYPE"C0805"
CDS_LIB"pure_quanta"
PART_NUMBER"CH622KMEA03";
"B"
$PN"2"16;
"A"
$PN"1"17;
%"Q_CAPP"
"1","(-1300,3150)","0","pure_quanta","I46";
;
LOCATION"PC6513"
$SEC"1"
CDS_SEC"1"
PACK_TYPE"SMLF"
VOLTAGE"2.5V"
VALUE"390UF"
MATERIAL"ALUM"
TOLERANCE"20%"
CDS_LIB"pure_quanta"
PART_NUMBER"CC7390JMZ13";
"A"
$PN"1"17;
"B"
$PN"2"16;
%"UNIVERSAL_GND"
"1","(-975,2775)","0","pure_quanta_power","I47";
;
CDS_LIB"pure_quanta_power"
HDL_POWER"GND";
"A"16;
%"Q_CAPP"
"1","(-1000,3150)","0","pure_quanta","I48";
;
LOCATION"PC6805"
$SEC"1"
CDS_SEC"1"
PACK_TYPE"SMLF"
VALUE"390UF"
TOLERANCE"20%"
MATERIAL"ALUM"
VOLTAGE"2.5V"
CDS_LIB"pure_quanta"
PART_NUMBER"CC7390JMZ13";
"A"
$PN"1"17;
"B"
$PN"2"16;
%"Q_CAP"
"1","(-675,3150)","0","pure_quanta","I49";
;
LOCATION"PC6514"
SEC"1"
VOLTAGE"25V"
TOLERANCE"10%"
VALUE"0.1UF"
PACK_TYPE"0402"
MATERIAL"X7R"
SEC_TYPE"0402"
CDS_LIB"pure_quanta"
PART_NUMBER"CH4104K1B00";
"B"
$PN"2"16;
"A"
$PN"1"17;
%"Q_CAP"
"1","(-8450,3200)","2","pure_quanta","I5";
;
LOCATION"C6757"
$SEC"1"
CDS_SEC"1"
VALUE"0.1UF"
MATERIAL"EMPTY"
VOLTAGE"25V"
TOLERANCE"10%"
PACK_TYPE"0402"
CDS_LIB"pure_quanta"
PART_NUMBER"CH4104K1B00";
"B"
$PN"2"1;
"A"
$PN"1"19;
%"P1V0"
"1","(-375,3775)","0","pure_quanta_power","I50";
;
HDL_POWER"P1V8_CPU0_RT_1D"
CDS_LIB"pure_quanta_power";
"A"17;
%"MPQ8633BGLEC838Z"
"1","(-5625,3225)","0","pure_quanta","I51";
;
LOCATION"PU6500"
$SEC"1"
CDS_SEC"1"
MATERIAL"IC"
VALUE"MPQ8633BGLE-C838-Z"
PART_TYPE"SMLF"
CDS_LIB"pure_quanta"
NEEDS_NO_SIZE"TRUE"
CDS_LMAN_SYM_OUTLINE"-250,725,250,-725"
PART_NUMBER"AL008633005";
"VIN2"
$PN"21"28;
"CS"
$PN"3"26;
"MODE"
$PN"4"23;
"TRK_REF"
$PN"5"24;
"SW"
$PN"20"12;
"RGND"
$PN"6"7;
"VCC"
$PN"19"27;
"AGND"
$PN"2"15;
"FB"
$PN"7"21;
"BST"
$PN"1"22;
"EN"
$PN"8"19;
"PGND"
$PN"11_18"15;
"PGOOD"
$PN"9"13;
"VIN1"
$PN"10"28;
%"Q_CAP"
"1","(-1575,3150)","0","pure_quanta","I52";
;
LOCATION"PC6512"
$SEC"1"
CDS_SEC"1"
VALUE"22UF"
VOLTAGE"4V"
PACK_TYPE"C0805"
MATERIAL"X6S"
TOLERANCE"20%"
CDS_LIB"pure_quanta"
PART_NUMBER"CH622KMEA03";
"B"
$PN"2"16;
"A"
$PN"1"17;
%"Q_CAP"
"1","(-6450,3975)","0","pure_quanta","I56";
;
LOCATION"PC6902"
$SEC"1"
CDS_SEC"1"
TOLERANCE"20%"
PACK_TYPE"C0805"
MATERIAL"X6S"
VOLTAGE"16V"
VALUE"22UF"
CDS_LIB"pure_quanta"
PART_NUMBER"CH6223MEA01";
"B"
$PN"2"14;
"A"
$PN"1"28;
%"Q_CAP"
"1","(-6650,3975)","0","pure_quanta","I57";
;
LOCATION"PC6901"
$SEC"1"
CDS_SEC"1"
PACK_TYPE"C0805"
MATERIAL"X6S"
TOLERANCE"20%"
VOLTAGE"16V"
VALUE"22UF"
CDS_LIB"pure_quanta"
PART_NUMBER"CH6223MEA01";
"B"
$PN"2"14;
"A"
$PN"1"28;
%"Q_CAP"
"1","(-6850,3975)","0","pure_quanta","I58";
;
LOCATION"PC6900"
$SEC"1"
CDS_SEC"1"
PACK_TYPE"C0805"
MATERIAL"X6S"
TOLERANCE"20%"
VOLTAGE"16V"
VALUE"22UF"
CDS_LIB"pure_quanta"
PART_NUMBER"CH6223MEA01";
"B"
$PN"2"14;
"A"
$PN"1"28;
%"Q_CAPP"
"1","(-8450,3975)","2","pure_quanta","I6";
;
LOCATION"PC6800"
$SEC"1"
CDS_SEC"1"
TOLERANCE"20%"
VALUE"270UF"
PACK_TYPE"SMLF"
MATERIAL"OSCON"
VOLTAGE"16V"
CDS_LIB"pure_quanta"
PART_NUMBER"CC72703MZ11";
"A"
$PN"1"28;
"B"
$PN"2"14;
%"Q_CAP"
"1","(-8300,3975)","0","pure_quanta","I7";
;
LOCATION"PC6802"
$SEC"1"
CDS_SEC"1"
MATERIAL"X6S"
VOLTAGE"16V"
VALUE"22UF"
TOLERANCE"20%"
PACK_TYPE"C0805"
CDS_LIB"pure_quanta"
PART_NUMBER"CH6223MEA01";
"B"
$PN"2"14;
"A"
$PN"1"28;
%"P1V0_AUX"
"1","(-9100,4375)","0","mstr_symbols","I8";
;
HDL_POWER"P12V_AUX"
ROOM"VR_DDR1_POWER_STAGE"
VOLTAGE"1.0V"
CDS_LIB"mstr_symbols"
BODY_TYPE"PLUMBING";
"A"18;
%"Q_INDUCTOR"
"1","(-8750,4200)","0","pure_quanta","I9";
;
LOCATION"PL6500"
$SEC"1"
CDS_SEC"1"
VALUE"100NH/16A"
PACK_TYPE"SMLF"
MATERIAL"IND"
CDS_LIB"pure_quanta"
NEEDS_NO_SIZE"TRUE"
PART_NUMBER"CV+10G0MZ04";
"1"
$PN"1"18;
"2"
$PN"2"28;
END.
